# TIMECARD (Time Appliance Project (Time Card)) — schematic netlist excerpt (pin names and nets, part order shuffled) for the footprints in the layout excerpt that follows; sources: Cadence DE-HDL packaged netlist, KiCad conversion of R4006-B0001-02_R01.brd

R333  RESISTOR  4.7KOHM 1%  pkg SMC_0402R_H016  page 17 : \1\ = XP3R3V_FPGA ; \2\ = UNNAMED_6_LM75BDPTSSOP8_I34_A2
R139  RESISTOR  33OHM 1%  pkg SMC_0402R_H016  page 26 : \1\ = UNNAMED_14_RESISTOR_I58_2 ; \2\ = XP2R5V_FPGA

(kicad_pcb
	(version 20260206)
	(generator "pcbnew")
	(generator_version "10.0")
	(general
		(thickness 1.6)
		(legacy_teardrops no)
	)
	(paper "A4")
	(title_block
		(title "timecard-production-celestica-r4006 — R4006-B0001-02_R01.brd")
		(comment 1 "Time Appliance Project (Time Card) / footprints 791-792 of 1113")
	)
	(layers
		(0 "F.Cu" signal "TOP")
		(4 "In1.Cu" signal "L02_GND1")
		(6 "In2.Cu" signal "L03_SIG1")
		(8 "In3.Cu" signal "L04_GND2")
		(10 "In4.Cu" signal "L05_VCC1")
		(12 "In5.Cu" signal "L06_VCC2")
		(14 "In6.Cu" signal "L07_GND3")
		(16 "In7.Cu" signal "L08_SIG2")
		(18 "In8.Cu" signal "L09_GND4")
		(2 "B.Cu" signal "BOTTOM")
		(9 "F.Adhes" user "F.Adhesive")
		(11 "B.Adhes" user "B.Adhesive")
		(13 "F.Paste" user "Package Geometry/Pastemask Top")
		(15 "B.Paste" user "Package Geometry/Pastemask Bottom")
		(5 "F.SilkS" user "Ref Des/Silkscreen Top")
		(7 "B.SilkS" user "Ref Des/Silkscreen Bottom")
		(1 "F.Mask" user "Board Geometry/Soldermask Top")
		(3 "B.Mask" user "Board Geometry/Soldermask Bottom")
		(17 "Dwgs.User" user "User.Drawings")
		(19 "Cmts.User" user "User.Comments")
		(21 "Eco1.User" user "User.Eco1")
		(23 "Eco2.User" user "User.Eco2")
		(25 "Edge.Cuts" user "Board Geometry/Outline")
		(27 "Margin" user)
		(31 "F.CrtYd" user "Package Geometry/Place Bound Top")
		(29 "B.CrtYd" user "Package Geometry/Place Bound Bottom")
		(35 "F.Fab" user "Ref Des/Assembly Top")
		(33 "B.Fab" user "Ref Des/Assembly Bottom")
	)
	(footprint ""
		(layer "B.Cu")
		(at 8.509 -72.39 -90)
		(property "Reference" "R333"
			(at 0.381 -2.62763 270)
			(unlocked yes)
			(layer "B.SilkS")
			(effects
				(font
					(size 0.7874 0.5842)
					(thickness 0.1524)
				)
				(justify mirror)
			)
		)
		(property "Value" "VAL*"
			(at -0.02032 2.13233 270)
			(unlocked yes)
			(layer "B.Fab")
			(hide yes)
			(effects
				(font
					(size 0.7874 0.5842)
					(thickness 0.1524)
				)
				(justify mirror)
			)
		)
		(property "Tolerance" "TOL*"
			(at -0.044704 3.05435 270)
			(unlocked yes)
			(layer "Cmts.User")
			(hide yes)
			(effects
				(font
					(size 0.7874 0.5842)
					(thickness 0.1524)
				)
				(justify mirror)
			)
		)
		(property "User Part Number" "PARTNUM*"
			(at -0.02032 4.024884 270)
			(unlocked yes)
			(layer "Cmts.User")
			(hide yes)
			(effects
				(font
					(size 0.7874 0.5842)
					(thickness 0.1524)
				)
				(justify mirror)
			)
		)
		(property "Device Type" "RESISTOR-G155-14701-01,4.7KOHMA"
			(at -0.008382 1.210564 270)
			(unlocked yes)
			(layer "B.Fab")
			(hide yes)
			(effects
				(font
					(size 0.7874 0.5842)
					(thickness 0.1524)
				)
				(justify mirror)
			)
		)
		(duplicate_pad_numbers_are_jumpers no)
		(fp_line
			(start -1.143 0.5588)
			(end -1.143 -0.5588)
			(stroke
				(width 0.1)
				(type default)
			)
			(layer "B.SilkS")
		)
		(fp_line
			(start 1.143 0.5588)
			(end -1.143 0.5588)
			(stroke
				(width 0.1)
				(type default)
			)
			(layer "B.SilkS")
		)
		(fp_line
			(start -1.143 -0.5588)
			(end 1.143 -0.5588)
			(stroke
				(width 0.1)
				(type default)
			)
			(layer "B.SilkS")
		)
		(fp_line
			(start 1.143 -0.5588)
			(end 1.143 0.5588)
			(stroke
				(width 0.1)
				(type default)
			)
			(layer "B.SilkS")
		)
		(fp_rect
			(start 1.143 -0.5588)
			(end -1.143 0.5588)
			(stroke
				(width 0)
				(type default)
			)
			(fill no)
			(layer "B.CrtYd")
		)
		(fp_line
			(start -0.508 0.3048)
			(end -0.508 -0.3048)
			(stroke
				(width 0.1)
				(type default)
			)
			(layer "B.Fab")
		)
		(fp_line
			(start 0.508 0.3048)
			(end -0.508 0.3048)
			(stroke
				(width 0.1)
				(type default)
			)
			(layer "B.Fab")
		)
		(fp_line
			(start -0.508 -0.3048)
			(end 0.508 -0.3048)
			(stroke
				(width 0.1)
				(type default)
			)
			(layer "B.Fab")
		)
		(fp_line
			(start 0.508 -0.3048)
			(end 0.508 0.3048)
			(stroke
				(width 0.1)
				(type default)
			)
			(layer "B.Fab")
		)
		(pad "1" smd rect
			(at 0.5334 0 90)
			(size 0.7112 0.6096)
			(layers "B.Cu" "B.Mask" "B.Paste")
			(net "XP3R3V_FPGA")
		)
		(pad "2" smd rect
			(at -0.5334 0 90)
			(size 0.7112 0.6096)
			(layers "B.Cu" "B.Mask" "B.Paste")
			(net "UNNAMED_6_LM75BDPTSSOP8_I34_A2")
		)
		(zone
			(layer "B.Cu")
			(hatch none 0.5)
			(connect_pads
				(clearance 0)
			)
			(min_thickness 0.25)
			(keepout
				(tracks allowed)
				(vias not_allowed)
				(pads allowed)
				(copperpour not_allowed)
				(footprints allowed)
			)
			(placement
				(enabled no)
				(sheetname "")
			)
			(fill
				(thermal_gap 0.5)
				(thermal_bridge_width 0.5)
				(island_removal_mode 0)
			)
			(polygon
				(pts
					(xy 8.8138 -72.3138) (xy 8.8138 -72.4662) (xy 8.2042 -72.4662) (xy 8.2042 -72.3138)
				)
			)
		)
	)
	(footprint ""
		(layer "B.Cu")
		(at 140.97 -103.378)
		(property "Reference" "R139"
			(at -0.889 3.72237 0)
			(unlocked yes)
			(layer "B.SilkS")
			(effects
				(font
					(size 0.7874 0.5842)
					(thickness 0.1524)
				)
				(justify mirror)
			)
		)
		(property "Value" "VAL*"
			(at -0.02032 2.13233 0)
			(unlocked yes)
			(layer "B.Fab")
			(hide yes)
			(effects
				(font
					(size 0.7874 0.5842)
					(thickness 0.1524)
				)
				(justify mirror)
			)
		)
		(property "Tolerance" "TOL*"
			(at -0.044704 3.05435 0)
			(unlocked yes)
			(layer "Cmts.User")
			(hide yes)
			(effects
				(font
					(size 0.7874 0.5842)
					(thickness 0.1524)
				)
				(justify mirror)
			)
		)
		(property "User Part Number" "PARTNUM*"
			(at -0.02032 4.024884 0)
			(unlocked yes)
			(layer "Cmts.User")
			(hide yes)
			(effects
				(font
					(size 0.7874 0.5842)
					(thickness 0.1524)
				)
				(justify mirror)
			)
		)
		(property "Device Type" "RESISTOR-G155-133R0-01,33OHM,1%"
			(at -0.008382 1.210564 0)
			(unlocked yes)
			(layer "B.Fab")
			(hide yes)
			(effects
				(font
					(size 0.7874 0.5842)
					(thickness 0.1524)
				)
				(justify mirror)
			)
		)
		(duplicate_pad_numbers_are_jumpers no)
		(fp_line
			(start -1.143 -0.5588)
			(end 1.143 -0.5588)
			(stroke
				(width 0.1)
				(type default)
			)
			(layer "B.SilkS")
		)
		(fp_line
			(start -1.143 0.5588)
			(end -1.143 -0.5588)
			(stroke
				(width 0.1)
				(type default)
			)
			(layer "B.SilkS")
		)
		(fp_line
			(start 1.143 -0.5588)
			(end 1.143 0.5588)
			(stroke
				(width 0.1)
				(type default)
			)
			(layer "B.SilkS")
		)
		(fp_line
			(start 1.143 0.5588)
			(end -1.143 0.5588)
			(stroke
				(width 0.1)
				(type default)
			)
			(layer "B.SilkS")
		)
		(fp_rect
			(start -1.143 -0.5588)
			(end 1.143 0.5588)
			(stroke
				(width 0)
				(type default)
			)
			(fill no)
			(layer "B.CrtYd")
		)
		(fp_line
			(start -0.508 -0.3048)
			(end 0.508 -0.3048)
			(stroke
				(width 0.1)
				(type default)
			)
			(layer "B.Fab")
		)
		(fp_line
			(start -0.508 0.3048)
			(end -0.508 -0.3048)
			(stroke
				(width 0.1)
				(type default)
			)
			(layer "B.Fab")
		)
		(fp_line
			(start 0.508 -0.3048)
			(end 0.508 0.3048)
			(stroke
				(width 0.1)
				(type default)
			)
			(layer "B.Fab")
		)
		(fp_line
			(start 0.508 0.3048)
			(end -0.508 0.3048)
			(stroke
				(width 0.1)
				(type default)
			)
			(layer "B.Fab")
		)
		(pad "1" smd rect
			(at 0.5334 0 180)
			(size 0.7112 0.6096)
			(layers "B.Cu" "B.Mask" "B.Paste")
			(net "UNNAMED_14_RESISTOR_I58_2")
		)
		(pad "2" smd rect
			(at -0.5334 0 180)
			(size 0.7112 0.6096)
			(layers "B.Cu" "B.Mask" "B.Paste")
			(net "XP2R5V_FPGA")
		)
		(zone
			(layer "B.Cu")
			(hatch none 0.5)
			(connect_pads
				(clearance 0)
			)
			(min_thickness 0.25)
			(keepout
				(tracks allowed)
				(vias not_allowed)
				(pads allowed)
				(copperpour not_allowed)
				(footprints allowed)
			)
			(placement
				(enabled no)
				(sheetname "")
			)
			(fill
				(thermal_gap 0.5)
				(thermal_bridge_width 0.5)
				(island_removal_mode 0)
			)
			(polygon
				(pts
					(xy 140.8938 -103.6828) (xy 140.8938 -103.0732) (xy 141.0462 -103.0732) (xy 141.0462 -103.6828)
				)
			)
		)
	)
)
